(kicad_pcb
	(version 20260206)
	(generator "pcbnew")
	(generator_version "10.0")
	(general
		(thickness 1.6)
		(legacy_teardrops no)
	)
	(paper "A4")
	(title_block
		(title "04192023_DAF0TMB3IC0_F0TG_MB_C_brd_V02_OCP.brd")
		(comment 1 "Grand Teton / footprints 1064-1070 of 8354")
	)
	(layers
		(0 "F.Cu" signal "TOP")
		(4 "In1.Cu" signal "GND")
		(6 "In2.Cu" signal "IN1")
		(8 "In3.Cu" signal "GND1")
		(10 "In4.Cu" signal "IN2")
		(12 "In5.Cu" signal "GND2")
		(14 "In6.Cu" signal "IN3")
		(16 "In7.Cu" signal "GND3")
		(18 "In8.Cu" signal "VCC")
		(20 "In9.Cu" signal "VCC1")
		(22 "In10.Cu" signal "GND4")
		(24 "In11.Cu" signal "IN4")
		(26 "In12.Cu" signal "GND5")
		(28 "In13.Cu" signal "IN5")
		(30 "In14.Cu" signal "GND6")
		(32 "In15.Cu" signal "IN6")
		(34 "In16.Cu" signal "GND7")
		(2 "B.Cu" signal "BOTTOM")
		(9 "F.Adhes" user "F.Adhesive")
		(11 "B.Adhes" user "B.Adhesive")
		(13 "F.Paste" user "Package Geometry/Pastemask Top")
		(15 "B.Paste" user "Package Geometry/Pastemask Bottom")
		(5 "F.SilkS" user "Ref Des/Silkscreen Top")
		(7 "B.SilkS" user "Ref Des/Silkscreen Bottom")
		(1 "F.Mask" user "Board Geometry/Soldermask Top")
		(3 "B.Mask" user "Board Geometry/Soldermask Bottom")
		(17 "Dwgs.User" user "User.Drawings")
		(19 "Cmts.User" user "User.Comments")
		(21 "Eco1.User" user "User.Eco1")
		(23 "Eco2.User" user "User.Eco2")
		(25 "Edge.Cuts" user "Board Geometry/Outline")
		(27 "Margin" user)
		(31 "F.CrtYd" user "Package Geometry/Place Bound Top")
		(29 "B.CrtYd" user "Package Geometry/Place Bound Bottom")
		(35 "F.Fab" user "Ref Des/Assembly Top")
		(33 "B.Fab" user "Ref Des/Assembly Bottom")
	)
	(footprint ""
		(layer "F.Cu")
		(at 51.577494 -32.277558 90)
		(property "Reference" "C1841"
			(at 0 0 90)
			(layer "F.SilkS")
			(hide yes)
			(effects
				(font
					(size 1.27 1.27)
				)
			)
		)
		(property "Value" ""
			(at 0 0 90)
			(layer "F.Fab")
			(effects
				(font
					(size 1.27 1.27)
				)
			)
		)
		(duplicate_pad_numbers_are_jumpers no)
		(fp_line
			(start 0.7874 -0.4064)
			(end 0.7874 0.4064)
			(stroke
				(width 0.1524)
				(type default)
			)
			(layer "F.SilkS")
		)
		(fp_line
			(start -0.7874 -0.4064)
			(end 0.7874 -0.4064)
			(stroke
				(width 0.1524)
				(type default)
			)
			(layer "F.SilkS")
		)
		(fp_line
			(start 0.7874 0.4064)
			(end -0.7874 0.4064)
			(stroke
				(width 0.1524)
				(type default)
			)
			(layer "F.SilkS")
		)
		(fp_line
			(start -0.7874 0.4064)
			(end -0.7874 -0.4064)
			(stroke
				(width 0.1524)
				(type default)
			)
			(layer "F.SilkS")
		)
		(fp_line
			(start -0.12065 -0.305054)
			(end -0.12065 -0.2794)
			(stroke
				(width 0.1)
				(type default)
			)
			(layer "F.Fab")
		)
		(fp_line
			(start -0.67945 -0.305054)
			(end -0.12065 -0.305054)
			(stroke
				(width 0.1)
				(type default)
			)
			(layer "F.Fab")
		)
		(fp_line
			(start 0.67945 -0.3048)
			(end 0.67945 0.3048)
			(stroke
				(width 0.1)
				(type default)
			)
			(layer "F.Fab")
		)
		(fp_line
			(start 0.12065 -0.3048)
			(end 0.67945 -0.3048)
			(stroke
				(width 0.1)
				(type default)
			)
			(layer "F.Fab")
		)
		(fp_line
			(start 0.12065 -0.2794)
			(end 0.12065 -0.3048)
			(stroke
				(width 0.1)
				(type default)
			)
			(layer "F.Fab")
		)
		(fp_line
			(start -0.12065 -0.2794)
			(end 0.12065 -0.2794)
			(stroke
				(width 0.1)
				(type default)
			)
			(layer "F.Fab")
		)
		(fp_line
			(start 0.120396 0.2794)
			(end -0.12065 0.2794)
			(stroke
				(width 0.1)
				(type default)
			)
			(layer "F.Fab")
		)
		(fp_line
			(start -0.12065 0.2794)
			(end -0.12065 0.3048)
			(stroke
				(width 0.1)
				(type default)
			)
			(layer "F.Fab")
		)
		(fp_line
			(start 0.67945 0.3048)
			(end 0.120396 0.3048)
			(stroke
				(width 0.1)
				(type default)
			)
			(layer "F.Fab")
		)
		(fp_line
			(start 0.120396 0.3048)
			(end 0.120396 0.2794)
			(stroke
				(width 0.1)
				(type default)
			)
			(layer "F.Fab")
		)
		(fp_line
			(start -0.12065 0.3048)
			(end -0.67945 0.3048)
			(stroke
				(width 0.1)
				(type default)
			)
			(layer "F.Fab")
		)
		(fp_line
			(start -0.67945 0.3048)
			(end -0.67945 -0.305054)
			(stroke
				(width 0.1)
				(type default)
			)
			(layer "F.Fab")
		)
		(pad "1" smd circle
			(at -0.40005 0 90)
			(size 0 0)
			(layers "F.Cu" "F.Mask" "F.Paste")
			(net "P3V3_AUX")
		)
		(pad "2" smd circle
			(at 0.40005 0 90)
			(size 0 0)
			(layers "F.Cu" "F.Mask" "F.Paste")
			(net "GND")
		)
	)
	(footprint ""
		(layer "F.Cu")
		(at 77.537564 -17.680178 -90)
		(property "Reference" "PR3806"
			(at 0 0 270)
			(layer "F.SilkS")
			(hide yes)
			(effects
				(font
					(size 1.27 1.27)
				)
			)
		)
		(property "Value" ""
			(at 0 0 270)
			(layer "F.Fab")
			(effects
				(font
					(size 1.27 1.27)
				)
			)
		)
		(duplicate_pad_numbers_are_jumpers no)
		(fp_line
			(start -0.7874 0.4064)
			(end -0.7874 -0.4064)
			(stroke
				(width 0.1524)
				(type default)
			)
			(layer "F.SilkS")
		)
		(fp_line
			(start 0.7874 0.4064)
			(end -0.7874 0.4064)
			(stroke
				(width 0.1524)
				(type default)
			)
			(layer "F.SilkS")
		)
		(fp_line
			(start -0.7874 -0.4064)
			(end 0.7874 -0.4064)
			(stroke
				(width 0.1524)
				(type default)
			)
			(layer "F.SilkS")
		)
		(fp_line
			(start 0.7874 -0.4064)
			(end 0.7874 0.4064)
			(stroke
				(width 0.1524)
				(type default)
			)
			(layer "F.SilkS")
		)
		(fp_line
			(start -0.67945 0.3048)
			(end -0.67945 -0.305054)
			(stroke
				(width 0.1)
				(type default)
			)
			(layer "F.Fab")
		)
		(fp_line
			(start -0.12065 0.3048)
			(end -0.67945 0.3048)
			(stroke
				(width 0.1)
				(type default)
			)
			(layer "F.Fab")
		)
		(fp_line
			(start 0.120396 0.3048)
			(end 0.120396 0.2794)
			(stroke
				(width 0.1)
				(type default)
			)
			(layer "F.Fab")
		)
		(fp_line
			(start 0.67945 0.3048)
			(end 0.120396 0.3048)
			(stroke
				(width 0.1)
				(type default)
			)
			(layer "F.Fab")
		)
		(fp_line
			(start -0.12065 0.2794)
			(end -0.12065 0.3048)
			(stroke
				(width 0.1)
				(type default)
			)
			(layer "F.Fab")
		)
		(fp_line
			(start 0.120396 0.2794)
			(end -0.12065 0.2794)
			(stroke
				(width 0.1)
				(type default)
			)
			(layer "F.Fab")
		)
		(fp_line
			(start -0.12065 -0.2794)
			(end 0.12065 -0.2794)
			(stroke
				(width 0.1)
				(type default)
			)
			(layer "F.Fab")
		)
		(fp_line
			(start 0.12065 -0.2794)
			(end 0.12065 -0.3048)
			(stroke
				(width 0.1)
				(type default)
			)
			(layer "F.Fab")
		)
		(fp_line
			(start 0.12065 -0.3048)
			(end 0.67945 -0.3048)
			(stroke
				(width 0.1)
				(type default)
			)
			(layer "F.Fab")
		)
		(fp_line
			(start 0.67945 -0.3048)
			(end 0.67945 0.3048)
			(stroke
				(width 0.1)
				(type default)
			)
			(layer "F.Fab")
		)
		(fp_line
			(start -0.67945 -0.305054)
			(end -0.12065 -0.305054)
			(stroke
				(width 0.1)
				(type default)
			)
			(layer "F.Fab")
		)
		(fp_line
			(start -0.12065 -0.305054)
			(end -0.12065 -0.2794)
			(stroke
				(width 0.1)
				(type default)
			)
			(layer "F.Fab")
		)
		(pad "1" smd circle
			(at -0.40005 0 270)
			(size 0 0)
			(layers "F.Cu" "F.Mask" "F.Paste")
			(net "P12V_OCP_UV_2")
		)
		(pad "2" smd circle
			(at 0.40005 0 270)
			(size 0 0)
			(layers "F.Cu" "F.Mask" "F.Paste")
			(net "P12V_OCP_OV_2")
		)
	)
	(footprint ""
		(layer "F.Cu")
		(at 209.628232 -124.21997)
		(property "Reference" "U75"
			(at -2.433574 -2.925318 0)
			(unlocked yes)
			(layer "F.SilkS")
			(effects
				(font
					(size 0.7874 0.5842)
					(thickness 0.1524)
				)
				(justify left)
			)
		)
		(property "Value" ""
			(at 0 0 0)
			(layer "F.Fab")
			(effects
				(font
					(size 1.27 1.27)
				)
			)
		)
		(duplicate_pad_numbers_are_jumpers no)
		(fp_line
			(start -1.695958 -1.124966)
			(end 1.695958 -1.124966)
			(stroke
				(width 0.1524)
				(type default)
			)
			(layer "F.SilkS")
		)
		(fp_line
			(start -1.695958 1.124966)
			(end -1.695958 -1.124966)
			(stroke
				(width 0.1524)
				(type default)
			)
			(layer "F.SilkS")
		)
		(fp_line
			(start 1.695958 -1.124966)
			(end 1.695958 1.124966)
			(stroke
				(width 0.1524)
				(type default)
			)
			(layer "F.SilkS")
		)
		(fp_line
			(start 1.695958 1.124966)
			(end -1.695958 1.124966)
			(stroke
				(width 0.1524)
				(type default)
			)
			(layer "F.SilkS")
		)
		(fp_poly
			(pts
				(xy -2.935478 -0.403352) (xy -2.935478 -1.023112) (xy -2.315718 -0.713232)
			)
			(stroke
				(width 0)
				(type default)
			)
			(fill yes)
			(layer "F.SilkS")
		)
		(fp_line
			(start -0.674878 -1.124966)
			(end 0.674878 -1.124966)
			(stroke
				(width 0.1)
				(type default)
			)
			(layer "F.Fab")
		)
		(fp_line
			(start -0.674878 1.124966)
			(end -0.674878 -1.124966)
			(stroke
				(width 0.1)
				(type default)
			)
			(layer "F.Fab")
		)
		(fp_line
			(start 0.674878 -1.124966)
			(end 0.674878 1.124966)
			(stroke
				(width 0.1)
				(type default)
			)
			(layer "F.Fab")
		)
		(fp_line
			(start 0.674878 1.124966)
			(end -0.674878 1.124966)
			(stroke
				(width 0.1)
				(type default)
			)
			(layer "F.Fab")
		)
		(fp_poly
			(pts
				(xy -2.4892 -0.959866) (xy -1.86944 -0.649986) (xy -2.4892 -0.340106)
			)
			(stroke
				(width 0)
				(type default)
			)
			(fill yes)
			(layer "F.Fab")
		)
		(pad "1" smd rect
			(at -0.94488 -0.649986 90)
			(size 0.3556 1.2446)
			(layers "F.Cu" "F.Mask" "F.Paste")
			(net "Net_10785")
		)
		(pad "2" smd rect
			(at -0.94488 0 90)
			(size 0.3556 1.2446)
			(layers "F.Cu" "F.Mask" "F.Paste")
			(net "RST_PERST_OCP_SFF_BUF_N")
		)
		(pad "3" smd rect
			(at -0.94488 0.649986 90)
			(size 0.3556 1.2446)
			(layers "F.Cu" "F.Mask" "F.Paste")
			(net "GND")
		)
		(pad "4" smd rect
			(at 0.94488 0.649986 90)
			(size 0.3556 1.2446)
			(layers "F.Cu" "F.Mask" "F.Paste")
			(net "RST_PERST_OCP_SFF_BUF2_N")
		)
		(pad "5" smd rect
			(at 0.94488 -0.649986 90)
			(size 0.3556 1.2446)
			(layers "F.Cu" "F.Mask" "F.Paste")
			(net "P3V3_AUX")
		)
	)
	(footprint ""
		(layer "F.Cu")
		(at 182.757572 -133.561074 -90)
		(property "Reference" "R1279"
			(at 0 0 270)
			(layer "F.SilkS")
			(hide yes)
			(effects
				(font
					(size 1.27 1.27)
				)
			)
		)
		(property "Value" ""
			(at 0 0 270)
			(layer "F.Fab")
			(effects
				(font
					(size 1.27 1.27)
				)
			)
		)
		(duplicate_pad_numbers_are_jumpers no)
		(fp_line
			(start -0.7874 0.4064)
			(end -0.7874 -0.4064)
			(stroke
				(width 0.1524)
				(type default)
			)
			(layer "F.SilkS")
		)
		(fp_line
			(start 0.7874 0.4064)
			(end -0.7874 0.4064)
			(stroke
				(width 0.1524)
				(type default)
			)
			(layer "F.SilkS")
		)
		(fp_line
			(start -0.7874 -0.4064)
			(end 0.7874 -0.4064)
			(stroke
				(width 0.1524)
				(type default)
			)
			(layer "F.SilkS")
		)
		(fp_line
			(start 0.7874 -0.4064)
			(end 0.7874 0.4064)
			(stroke
				(width 0.1524)
				(type default)
			)
			(layer "F.SilkS")
		)
		(fp_line
			(start -0.67945 0.3048)
			(end -0.67945 -0.305054)
			(stroke
				(width 0.1)
				(type default)
			)
			(layer "F.Fab")
		)
		(fp_line
			(start -0.12065 0.3048)
			(end -0.67945 0.3048)
			(stroke
				(width 0.1)
				(type default)
			)
			(layer "F.Fab")
		)
		(fp_line
			(start 0.120396 0.3048)
			(end 0.120396 0.2794)
			(stroke
				(width 0.1)
				(type default)
			)
			(layer "F.Fab")
		)
		(fp_line
			(start 0.67945 0.3048)
			(end 0.120396 0.3048)
			(stroke
				(width 0.1)
				(type default)
			)
			(layer "F.Fab")
		)
		(fp_line
			(start -0.12065 0.2794)
			(end -0.12065 0.3048)
			(stroke
				(width 0.1)
				(type default)
			)
			(layer "F.Fab")
		)
		(fp_line
			(start 0.120396 0.2794)
			(end -0.12065 0.2794)
			(stroke
				(width 0.1)
				(type default)
			)
			(layer "F.Fab")
		)
		(fp_line
			(start -0.12065 -0.2794)
			(end 0.12065 -0.2794)
			(stroke
				(width 0.1)
				(type default)
			)
			(layer "F.Fab")
		)
		(fp_line
			(start 0.12065 -0.2794)
			(end 0.12065 -0.3048)
			(stroke
				(width 0.1)
				(type default)
			)
			(layer "F.Fab")
		)
		(fp_line
			(start 0.12065 -0.3048)
			(end 0.67945 -0.3048)
			(stroke
				(width 0.1)
				(type default)
			)
			(layer "F.Fab")
		)
		(fp_line
			(start 0.67945 -0.3048)
			(end 0.67945 0.3048)
			(stroke
				(width 0.1)
				(type default)
			)
			(layer "F.Fab")
		)
		(fp_line
			(start -0.67945 -0.305054)
			(end -0.12065 -0.305054)
			(stroke
				(width 0.1)
				(type default)
			)
			(layer "F.Fab")
		)
		(fp_line
			(start -0.12065 -0.305054)
			(end -0.12065 -0.2794)
			(stroke
				(width 0.1)
				(type default)
			)
			(layer "F.Fab")
		)
		(pad "1" smd circle
			(at -0.40005 0 270)
			(size 0 0)
			(layers "F.Cu" "F.Mask" "F.Paste")
			(net "FM_P1_PCC1_N")
		)
		(pad "2" smd circle
			(at 0.40005 0 270)
			(size 0 0)
			(layers "F.Cu" "F.Mask" "F.Paste")
			(net "FM_P1_PCC1_R_N")
		)
	)
	(footprint ""
		(layer "F.Cu")
		(at 413.928306 -137.16762)
		(property "Reference" "PC1898"
			(at 0 0 0)
			(layer "F.SilkS")
			(hide yes)
			(effects
				(font
					(size 1.27 1.27)
				)
			)
		)
		(property "Value" ""
			(at 0 0 0)
			(layer "F.Fab")
			(effects
				(font
					(size 1.27 1.27)
				)
			)
		)
		(duplicate_pad_numbers_are_jumpers no)
		(fp_line
			(start -1.524 -0.762)
			(end 1.524 -0.762)
			(stroke
				(width 0.1524)
				(type default)
			)
			(layer "F.SilkS")
		)
		(fp_line
			(start -1.524 0.762)
			(end -1.524 -0.762)
			(stroke
				(width 0.1524)
				(type default)
			)
			(layer "F.SilkS")
		)
		(fp_line
			(start 1.524 -0.762)
			(end 1.524 0.762)
			(stroke
				(width 0.1524)
				(type default)
			)
			(layer "F.SilkS")
		)
		(fp_line
			(start 1.524 0.762)
			(end -1.524 0.762)
			(stroke
				(width 0.1524)
				(type default)
			)
			(layer "F.SilkS")
		)
		(fp_line
			(start -1.1049 -0.724916)
			(end -1.1049 0.724916)
			(stroke
				(width 0.1)
				(type default)
			)
			(layer "F.Fab")
		)
		(fp_line
			(start -1.1049 0.724916)
			(end 1.1049 0.724916)
			(stroke
				(width 0.1)
				(type default)
			)
			(layer "F.Fab")
		)
		(fp_line
			(start 1.1049 -0.724916)
			(end -1.1049 -0.724916)
			(stroke
				(width 0.1)
				(type default)
			)
			(layer "F.Fab")
		)
		(fp_line
			(start 1.1049 0.724916)
			(end 1.1049 -0.724916)
			(stroke
				(width 0.1)
				(type default)
			)
			(layer "F.Fab")
		)
		(pad "1" smd rect
			(at -0.889 0 180)
			(size 1.016 1.27)
			(layers "F.Cu" "F.Mask" "F.Paste")
			(net "SW_P5V_AUX_FLT")
		)
		(pad "2" smd rect
			(at 0.889 0 180)
			(size 1.016 1.27)
			(layers "F.Cu" "F.Mask" "F.Paste")
			(net "GND")
		)
	)
	(footprint ""
		(layer "F.Cu")
		(at 384.760978 -180.078634 -90)
		(property "Reference" "PC546"
			(at 0 0 270)
			(layer "F.SilkS")
			(hide yes)
			(effects
				(font
					(size 1.27 1.27)
				)
			)
		)
		(property "Value" ""
			(at 0 0 270)
			(layer "F.Fab")
			(effects
				(font
					(size 1.27 1.27)
				)
			)
		)
		(duplicate_pad_numbers_are_jumpers no)
		(fp_line
			(start -0.7874 0.4064)
			(end -0.7874 -0.4064)
			(stroke
				(width 0.1524)
				(type default)
			)
			(layer "F.SilkS")
		)
		(fp_line
			(start -0.362966 0.4064)
			(end -0.7874 0.4064)
			(stroke
				(width 0.1524)
				(type default)
			)
			(layer "F.SilkS")
		)
		(fp_line
			(start 0.7874 0.4064)
			(end 0.500634 0.4064)
			(stroke
				(width 0.1524)
				(type default)
			)
			(layer "F.SilkS")
		)
		(fp_line
			(start -0.7874 -0.4064)
			(end 0.7874 -0.4064)
			(stroke
				(width 0.1524)
				(type default)
			)
			(layer "F.SilkS")
		)
		(fp_line
			(start 0.7874 -0.4064)
			(end 0.7874 0.4064)
			(stroke
				(width 0.1524)
				(type default)
			)
			(layer "F.SilkS")
		)
		(fp_line
			(start -0.67945 0.3048)
			(end -0.67945 -0.305054)
			(stroke
				(width 0.1)
				(type default)
			)
			(layer "F.Fab")
		)
		(fp_line
			(start -0.12065 0.3048)
			(end -0.67945 0.3048)
			(stroke
				(width 0.1)
				(type default)
			)
			(layer "F.Fab")
		)
		(fp_line
			(start 0.120396 0.3048)
			(end 0.120396 0.2794)
			(stroke
				(width 0.1)
				(type default)
			)
			(layer "F.Fab")
		)
		(fp_line
			(start 0.67945 0.3048)
			(end 0.120396 0.3048)
			(stroke
				(width 0.1)
				(type default)
			)
			(layer "F.Fab")
		)
		(fp_line
			(start -0.12065 0.2794)
			(end -0.12065 0.3048)
			(stroke
				(width 0.1)
				(type default)
			)
			(layer "F.Fab")
		)
		(fp_line
			(start 0.120396 0.2794)
			(end -0.12065 0.2794)
			(stroke
				(width 0.1)
				(type default)
			)
			(layer "F.Fab")
		)
		(fp_line
			(start -0.12065 -0.2794)
			(end 0.12065 -0.2794)
			(stroke
				(width 0.1)
				(type default)
			)
			(layer "F.Fab")
		)
		(fp_line
			(start 0.12065 -0.2794)
			(end 0.12065 -0.3048)
			(stroke
				(width 0.1)
				(type default)
			)
			(layer "F.Fab")
		)
		(fp_line
			(start 0.12065 -0.3048)
			(end 0.67945 -0.3048)
			(stroke
				(width 0.1)
				(type default)
			)
			(layer "F.Fab")
		)
		(fp_line
			(start 0.67945 -0.3048)
			(end 0.67945 0.3048)
			(stroke
				(width 0.1)
				(type default)
			)
			(layer "F.Fab")
		)
		(fp_line
			(start -0.67945 -0.305054)
			(end -0.12065 -0.305054)
			(stroke
				(width 0.1)
				(type default)
			)
			(layer "F.Fab")
		)
		(fp_line
			(start -0.12065 -0.305054)
			(end -0.12065 -0.2794)
			(stroke
				(width 0.1)
				(type default)
			)
			(layer "F.Fab")
		)
		(pad "1" smd circle
			(at -0.40005 0 270)
			(size 0 0)
			(layers "F.Cu" "F.Mask" "F.Paste")
			(net "PVDDCR_CPU0_P0_VCC3")
		)
		(pad "2" smd circle
			(at 0.40005 0 270)
			(size 0 0)
			(layers "F.Cu" "F.Mask" "F.Paste")
			(net "GND")
		)
	)
	(footprint ""
		(layer "F.Cu")
		(at 84.940902 -370.57203 -90)
		(property "Reference" "C728"
			(at 0 0 270)
			(layer "F.SilkS")
			(hide yes)
			(effects
				(font
					(size 1.27 1.27)
				)
			)
		)
		(property "Value" ""
			(at 0 0 270)
			(layer "F.Fab")
			(effects
				(font
					(size 1.27 1.27)
				)
			)
		)
		(duplicate_pad_numbers_are_jumpers no)
		(fp_line
			(start -0.299974 0.150114)
			(end -0.299974 -0.150114)
			(stroke
				(width 0.1)
				(type default)
			)
			(layer "F.Fab")
		)
		(fp_line
			(start 0.299974 0.150114)
			(end -0.299974 0.150114)
			(stroke
				(width 0.1)
				(type default)
			)
			(layer "F.Fab")
		)
		(fp_line
			(start -0.299974 -0.150114)
			(end 0.299974 -0.150114)
			(stroke
				(width 0.1)
				(type default)
			)
			(layer "F.Fab")
		)
		(fp_line
			(start 0.299974 -0.150114)
			(end 0.299974 0.150114)
			(stroke
				(width 0.1)
				(type default)
			)
			(layer "F.Fab")
		)
		(pad "1" smd rect
			(at -0.2667 0 270)
			(size 0.3048 0.381)
			(layers "F.Cu" "F.Mask" "F.Paste")
			(net "P5E_CPU1_P1_TX_C_DN<6>")
		)
		(pad "2" smd rect
			(at 0.2667 0 270)
			(size 0.3048 0.381)
			(layers "F.Cu" "F.Mask" "F.Paste")
			(net "P5E_CPU1_P1_TX_DN<6>")
		)
	)
)
